# T6G (Grand Teton) — schematic netlist excerpt (pin names and nets, part order shuffled) for the footprints in the layout excerpt that follows; sources: Cadence DE-HDL packaged netlist, KiCad conversion of 04192023_DAF0TMB3IC0_F0TG_MB_C_brd_V02_OCP.brd

PR3980  Q_RES  0 5% CHIP  pkg 0402LF  page 264 : A = HSC_VDD_R_3 ; B = HSC_VDD
C2360  Q_CAP  22UF 4V 20% X6S  pkg C0402  page 73 : A = PVDDCR_CPU1_P1 ; B = GND

(kicad_pcb
	(version 20260206)
	(generator "pcbnew")
	(generator_version "10.0")
	(general
		(thickness 1.6)
		(legacy_teardrops no)
	)
	(paper "A4")
	(title_block
		(title "04192023_DAF0TMB3IC0_F0TG_MB_C_brd_V02_OCP.brd")
		(comment 1 "Grand Teton / footprints 6854-6855 of 8354")
	)
	(layers
		(0 "F.Cu" signal "TOP")
		(4 "In1.Cu" signal "GND")
		(6 "In2.Cu" signal "IN1")
		(8 "In3.Cu" signal "GND1")
		(10 "In4.Cu" signal "IN2")
		(12 "In5.Cu" signal "GND2")
		(14 "In6.Cu" signal "IN3")
		(16 "In7.Cu" signal "GND3")
		(18 "In8.Cu" signal "VCC")
		(20 "In9.Cu" signal "VCC1")
		(22 "In10.Cu" signal "GND4")
		(24 "In11.Cu" signal "IN4")
		(26 "In12.Cu" signal "GND5")
		(28 "In13.Cu" signal "IN5")
		(30 "In14.Cu" signal "GND6")
		(32 "In15.Cu" signal "IN6")
		(34 "In16.Cu" signal "GND7")
		(2 "B.Cu" signal "BOTTOM")
		(9 "F.Adhes" user "F.Adhesive")
		(11 "B.Adhes" user "B.Adhesive")
		(13 "F.Paste" user "Package Geometry/Pastemask Top")
		(15 "B.Paste" user "Package Geometry/Pastemask Bottom")
		(5 "F.SilkS" user "Ref Des/Silkscreen Top")
		(7 "B.SilkS" user "Ref Des/Silkscreen Bottom")
		(1 "F.Mask" user "Board Geometry/Soldermask Top")
		(3 "B.Mask" user "Board Geometry/Soldermask Bottom")
		(17 "Dwgs.User" user "User.Drawings")
		(19 "Cmts.User" user "User.Comments")
		(21 "Eco1.User" user "User.Eco1")
		(23 "Eco2.User" user "User.Eco2")
		(25 "Edge.Cuts" user "Board Geometry/Outline")
		(27 "Margin" user)
		(31 "F.CrtYd" user "Package Geometry/Place Bound Top")
		(29 "B.CrtYd" user "Package Geometry/Place Bound Bottom")
		(35 "F.Fab" user "Ref Des/Assembly Top")
		(33 "B.Fab" user "Ref Des/Assembly Bottom")
	)
	(footprint ""
		(layer "B.Cu")
		(at 215.2523 -402.744432 -90)
		(property "Reference" "PR3980"
			(at 0 0 90)
			(layer "B.SilkS")
			(hide yes)
			(effects
				(font
					(size 1.27 1.27)
				)
				(justify mirror)
			)
		)
		(property "Value" ""
			(at 0 0 90)
			(layer "B.Fab")
			(effects
				(font
					(size 1.27 1.27)
				)
				(justify mirror)
			)
		)
		(duplicate_pad_numbers_are_jumpers no)
		(fp_line
			(start -0.7874 0.4064)
			(end 0.7874 0.4064)
			(stroke
				(width 0.1524)
				(type default)
			)
			(layer "B.SilkS")
		)
		(fp_line
			(start 0.7874 0.4064)
			(end 0.7874 -0.4064)
			(stroke
				(width 0.1524)
				(type default)
			)
			(layer "B.SilkS")
		)
		(fp_line
			(start -0.7874 -0.4064)
			(end -0.7874 0.4064)
			(stroke
				(width 0.1524)
				(type default)
			)
			(layer "B.SilkS")
		)
		(fp_line
			(start 0.7874 -0.4064)
			(end -0.7874 -0.4064)
			(stroke
				(width 0.1524)
				(type default)
			)
			(layer "B.SilkS")
		)
		(fp_line
			(start -0.67945 0.3048)
			(end -0.120396 0.3048)
			(stroke
				(width 0.1)
				(type default)
			)
			(layer "B.Fab")
		)
		(fp_line
			(start -0.120396 0.3048)
			(end -0.120396 0.2794)
			(stroke
				(width 0.1)
				(type default)
			)
			(layer "B.Fab")
		)
		(fp_line
			(start 0.12065 0.3048)
			(end 0.67945 0.3048)
			(stroke
				(width 0.1)
				(type default)
			)
			(layer "B.Fab")
		)
		(fp_line
			(start 0.67945 0.3048)
			(end 0.67945 -0.305054)
			(stroke
				(width 0.1)
				(type default)
			)
			(layer "B.Fab")
		)
		(fp_line
			(start -0.120396 0.2794)
			(end 0.12065 0.2794)
			(stroke
				(width 0.1)
				(type default)
			)
			(layer "B.Fab")
		)
		(fp_line
			(start 0.12065 0.2794)
			(end 0.12065 0.3048)
			(stroke
				(width 0.1)
				(type default)
			)
			(layer "B.Fab")
		)
		(fp_line
			(start -0.12065 -0.2794)
			(end -0.12065 -0.3048)
			(stroke
				(width 0.1)
				(type default)
			)
			(layer "B.Fab")
		)
		(fp_line
			(start 0.12065 -0.2794)
			(end -0.12065 -0.2794)
			(stroke
				(width 0.1)
				(type default)
			)
			(layer "B.Fab")
		)
		(fp_line
			(start -0.67945 -0.3048)
			(end -0.67945 0.3048)
			(stroke
				(width 0.1)
				(type default)
			)
			(layer "B.Fab")
		)
		(fp_line
			(start -0.12065 -0.3048)
			(end -0.67945 -0.3048)
			(stroke
				(width 0.1)
				(type default)
			)
			(layer "B.Fab")
		)
		(fp_line
			(start 0.12065 -0.305054)
			(end 0.12065 -0.2794)
			(stroke
				(width 0.1)
				(type default)
			)
			(layer "B.Fab")
		)
		(fp_line
			(start 0.67945 -0.305054)
			(end 0.12065 -0.305054)
			(stroke
				(width 0.1)
				(type default)
			)
			(layer "B.Fab")
		)
		(pad "1" smd circle
			(at 0.40005 0 90)
			(size 0 0)
			(layers "B.Cu" "B.Mask" "B.Paste")
			(net "HSC_VDD_R_3")
		)
		(pad "2" smd circle
			(at -0.40005 0 90)
			(size 0 0)
			(layers "B.Cu" "B.Mask" "B.Paste")
			(net "HSC_VDD")
		)
	)
	(footprint ""
		(layer "B.Cu")
		(at 100.878386 -267.529564)
		(property "Reference" "C2360"
			(at 0 0 0)
			(layer "B.SilkS")
			(hide yes)
			(effects
				(font
					(size 1.27 1.27)
				)
				(justify mirror)
			)
		)
		(property "Value" ""
			(at 0 0 0)
			(layer "B.Fab")
			(effects
				(font
					(size 1.27 1.27)
				)
				(justify mirror)
			)
		)
		(duplicate_pad_numbers_are_jumpers no)
		(fp_line
			(start -0.7874 -0.4064)
			(end -0.7874 0.4064)
			(stroke
				(width 0.1524)
				(type default)
			)
			(layer "B.SilkS")
		)
		(fp_line
			(start -0.7874 0.4064)
			(end 0.7874 0.4064)
			(stroke
				(width 0.1524)
				(type default)
			)
			(layer "B.SilkS")
		)
		(fp_line
			(start 0.7874 -0.4064)
			(end -0.7874 -0.4064)
			(stroke
				(width 0.1524)
				(type default)
			)
			(layer "B.SilkS")
		)
		(fp_line
			(start 0.7874 0.4064)
			(end 0.7874 -0.4064)
			(stroke
				(width 0.1524)
				(type default)
			)
			(layer "B.SilkS")
		)
		(fp_line
			(start -0.67945 -0.3048)
			(end -0.67945 0.3048)
			(stroke
				(width 0.1)
				(type default)
			)
			(layer "B.Fab")
		)
		(fp_line
			(start -0.67945 0.3048)
			(end -0.120396 0.3048)
			(stroke
				(width 0.1)
				(type default)
			)
			(layer "B.Fab")
		)
		(fp_line
			(start -0.12065 -0.3048)
			(end -0.67945 -0.3048)
			(stroke
				(width 0.1)
				(type default)
			)
			(layer "B.Fab")
		)
		(fp_line
			(start -0.12065 -0.2794)
			(end -0.12065 -0.3048)
			(stroke
				(width 0.1)
				(type default)
			)
			(layer "B.Fab")
		)
		(fp_line
			(start -0.120396 0.2794)
			(end 0.12065 0.2794)
			(stroke
				(width 0.1)
				(type default)
			)
			(layer "B.Fab")
		)
		(fp_line
			(start -0.120396 0.3048)
			(end -0.120396 0.2794)
			(stroke
				(width 0.1)
				(type default)
			)
			(layer "B.Fab")
		)
		(fp_line
			(start 0.12065 -0.305054)
			(end 0.12065 -0.2794)
			(stroke
				(width 0.1)
				(type default)
			)
			(layer "B.Fab")
		)
		(fp_line
			(start 0.12065 -0.2794)
			(end -0.12065 -0.2794)
			(stroke
				(width 0.1)
				(type default)
			)
			(layer "B.Fab")
		)
		(fp_line
			(start 0.12065 0.2794)
			(end 0.12065 0.3048)
			(stroke
				(width 0.1)
				(type default)
			)
			(layer "B.Fab")
		)
		(fp_line
			(start 0.12065 0.3048)
			(end 0.67945 0.3048)
			(stroke
				(width 0.1)
				(type default)
			)
			(layer "B.Fab")
		)
		(fp_line
			(start 0.67945 -0.305054)
			(end 0.12065 -0.305054)
			(stroke
				(width 0.1)
				(type default)
			)
			(layer "B.Fab")
		)
		(fp_line
			(start 0.67945 0.3048)
			(end 0.67945 -0.305054)
			(stroke
				(width 0.1)
				(type default)
			)
			(layer "B.Fab")
		)
		(pad "1" smd circle
			(at 0.40005 0 180)
			(size 0 0)
			(layers "B.Cu" "B.Mask" "B.Paste")
			(net "PVDDCR_CPU1_P1")
		)
		(pad "2" smd circle
			(at -0.40005 0 180)
			(size 0 0)
			(layers "B.Cu" "B.Mask" "B.Paste")
			(net "GND")
		)
	)
)
